(kicad_pcb
	(version 20260206)
	(generator "pcbnew")
	(generator_version "10.0")
	(general
		(thickness 1.6)
		(legacy_teardrops no)
	)
	(paper "A4")
	(title_block
		(title "04192023_DAF0TMB3IC0_F0TG_MB_C_brd_V02_OCP.brd")
		(comment 1 "Grand Teton / footprints 3780-3785 of 8354")
	)
	(layers
		(0 "F.Cu" signal "TOP")
		(4 "In1.Cu" signal "GND")
		(6 "In2.Cu" signal "IN1")
		(8 "In3.Cu" signal "GND1")
		(10 "In4.Cu" signal "IN2")
		(12 "In5.Cu" signal "GND2")
		(14 "In6.Cu" signal "IN3")
		(16 "In7.Cu" signal "GND3")
		(18 "In8.Cu" signal "VCC")
		(20 "In9.Cu" signal "VCC1")
		(22 "In10.Cu" signal "GND4")
		(24 "In11.Cu" signal "IN4")
		(26 "In12.Cu" signal "GND5")
		(28 "In13.Cu" signal "IN5")
		(30 "In14.Cu" signal "GND6")
		(32 "In15.Cu" signal "IN6")
		(34 "In16.Cu" signal "GND7")
		(2 "B.Cu" signal "BOTTOM")
		(9 "F.Adhes" user "F.Adhesive")
		(11 "B.Adhes" user "B.Adhesive")
		(13 "F.Paste" user "Package Geometry/Pastemask Top")
		(15 "B.Paste" user "Package Geometry/Pastemask Bottom")
		(5 "F.SilkS" user "Ref Des/Silkscreen Top")
		(7 "B.SilkS" user "Ref Des/Silkscreen Bottom")
		(1 "F.Mask" user "Board Geometry/Soldermask Top")
		(3 "B.Mask" user "Board Geometry/Soldermask Bottom")
		(17 "Dwgs.User" user "User.Drawings")
		(19 "Cmts.User" user "User.Comments")
		(21 "Eco1.User" user "User.Eco1")
		(23 "Eco2.User" user "User.Eco2")
		(25 "Edge.Cuts" user "Board Geometry/Outline")
		(27 "Margin" user)
		(31 "F.CrtYd" user "Package Geometry/Place Bound Top")
		(29 "B.CrtYd" user "Package Geometry/Place Bound Bottom")
		(35 "F.Fab" user "Ref Des/Assembly Top")
		(33 "B.Fab" user "Ref Des/Assembly Bottom")
	)
	(footprint ""
		(layer "F.Cu")
		(at 106.892598 -18.20291)
		(property "Reference" "R3554"
			(at 0 0 0)
			(layer "F.SilkS")
			(hide yes)
			(effects
				(font
					(size 1.27 1.27)
				)
			)
		)
		(property "Value" ""
			(at 0 0 0)
			(layer "F.Fab")
			(effects
				(font
					(size 1.27 1.27)
				)
			)
		)
		(duplicate_pad_numbers_are_jumpers no)
		(fp_line
			(start -0.7874 -0.4064)
			(end 0.7874 -0.4064)
			(stroke
				(width 0.1524)
				(type default)
			)
			(layer "F.SilkS")
		)
		(fp_line
			(start -0.7874 0.4064)
			(end -0.7874 -0.4064)
			(stroke
				(width 0.1524)
				(type default)
			)
			(layer "F.SilkS")
		)
		(fp_line
			(start 0.7874 -0.4064)
			(end 0.7874 0.4064)
			(stroke
				(width 0.1524)
				(type default)
			)
			(layer "F.SilkS")
		)
		(fp_line
			(start 0.7874 0.4064)
			(end -0.7874 0.4064)
			(stroke
				(width 0.1524)
				(type default)
			)
			(layer "F.SilkS")
		)
		(fp_line
			(start -0.67945 -0.305054)
			(end -0.12065 -0.305054)
			(stroke
				(width 0.1)
				(type default)
			)
			(layer "F.Fab")
		)
		(fp_line
			(start -0.67945 0.3048)
			(end -0.67945 -0.305054)
			(stroke
				(width 0.1)
				(type default)
			)
			(layer "F.Fab")
		)
		(fp_line
			(start -0.12065 -0.305054)
			(end -0.12065 -0.2794)
			(stroke
				(width 0.1)
				(type default)
			)
			(layer "F.Fab")
		)
		(fp_line
			(start -0.12065 -0.2794)
			(end 0.12065 -0.2794)
			(stroke
				(width 0.1)
				(type default)
			)
			(layer "F.Fab")
		)
		(fp_line
			(start -0.12065 0.2794)
			(end -0.12065 0.3048)
			(stroke
				(width 0.1)
				(type default)
			)
			(layer "F.Fab")
		)
		(fp_line
			(start -0.12065 0.3048)
			(end -0.67945 0.3048)
			(stroke
				(width 0.1)
				(type default)
			)
			(layer "F.Fab")
		)
		(fp_line
			(start 0.120396 0.2794)
			(end -0.12065 0.2794)
			(stroke
				(width 0.1)
				(type default)
			)
			(layer "F.Fab")
		)
		(fp_line
			(start 0.120396 0.3048)
			(end 0.120396 0.2794)
			(stroke
				(width 0.1)
				(type default)
			)
			(layer "F.Fab")
		)
		(fp_line
			(start 0.12065 -0.3048)
			(end 0.67945 -0.3048)
			(stroke
				(width 0.1)
				(type default)
			)
			(layer "F.Fab")
		)
		(fp_line
			(start 0.12065 -0.2794)
			(end 0.12065 -0.3048)
			(stroke
				(width 0.1)
				(type default)
			)
			(layer "F.Fab")
		)
		(fp_line
			(start 0.67945 -0.3048)
			(end 0.67945 0.3048)
			(stroke
				(width 0.1)
				(type default)
			)
			(layer "F.Fab")
		)
		(fp_line
			(start 0.67945 0.3048)
			(end 0.120396 0.3048)
			(stroke
				(width 0.1)
				(type default)
			)
			(layer "F.Fab")
		)
		(pad "1" smd circle
			(at -0.40005 0)
			(size 0 0)
			(layers "F.Cu" "F.Mask" "F.Paste")
			(net "SMB_LM75_3_3V3AUX_SDA")
		)
		(pad "2" smd circle
			(at 0.40005 0)
			(size 0 0)
			(layers "F.Cu" "F.Mask" "F.Paste")
			(net "SMB_LM75_3_3V3AUX_SDA_R1")
		)
	)
	(footprint ""
		(layer "F.Cu")
		(at 182.14594 -406.659842 90)
		(property "Reference" "R3925"
			(at 0 0 90)
			(layer "F.SilkS")
			(hide yes)
			(effects
				(font
					(size 1.27 1.27)
				)
			)
		)
		(property "Value" ""
			(at 0 0 90)
			(layer "F.Fab")
			(effects
				(font
					(size 1.27 1.27)
				)
			)
		)
		(duplicate_pad_numbers_are_jumpers no)
		(fp_line
			(start 0.7874 -0.4064)
			(end 0.7874 0.4064)
			(stroke
				(width 0.1524)
				(type default)
			)
			(layer "F.SilkS")
		)
		(fp_line
			(start -0.7874 -0.4064)
			(end 0.7874 -0.4064)
			(stroke
				(width 0.1524)
				(type default)
			)
			(layer "F.SilkS")
		)
		(fp_line
			(start 0.7874 0.4064)
			(end -0.7874 0.4064)
			(stroke
				(width 0.1524)
				(type default)
			)
			(layer "F.SilkS")
		)
		(fp_line
			(start -0.7874 0.4064)
			(end -0.7874 -0.4064)
			(stroke
				(width 0.1524)
				(type default)
			)
			(layer "F.SilkS")
		)
		(fp_line
			(start -0.12065 -0.305054)
			(end -0.12065 -0.2794)
			(stroke
				(width 0.1)
				(type default)
			)
			(layer "F.Fab")
		)
		(fp_line
			(start -0.67945 -0.305054)
			(end -0.12065 -0.305054)
			(stroke
				(width 0.1)
				(type default)
			)
			(layer "F.Fab")
		)
		(fp_line
			(start 0.67945 -0.3048)
			(end 0.67945 0.3048)
			(stroke
				(width 0.1)
				(type default)
			)
			(layer "F.Fab")
		)
		(fp_line
			(start 0.12065 -0.3048)
			(end 0.67945 -0.3048)
			(stroke
				(width 0.1)
				(type default)
			)
			(layer "F.Fab")
		)
		(fp_line
			(start 0.12065 -0.2794)
			(end 0.12065 -0.3048)
			(stroke
				(width 0.1)
				(type default)
			)
			(layer "F.Fab")
		)
		(fp_line
			(start -0.12065 -0.2794)
			(end 0.12065 -0.2794)
			(stroke
				(width 0.1)
				(type default)
			)
			(layer "F.Fab")
		)
		(fp_line
			(start 0.120396 0.2794)
			(end -0.12065 0.2794)
			(stroke
				(width 0.1)
				(type default)
			)
			(layer "F.Fab")
		)
		(fp_line
			(start -0.12065 0.2794)
			(end -0.12065 0.3048)
			(stroke
				(width 0.1)
				(type default)
			)
			(layer "F.Fab")
		)
		(fp_line
			(start 0.67945 0.3048)
			(end 0.120396 0.3048)
			(stroke
				(width 0.1)
				(type default)
			)
			(layer "F.Fab")
		)
		(fp_line
			(start 0.120396 0.3048)
			(end 0.120396 0.2794)
			(stroke
				(width 0.1)
				(type default)
			)
			(layer "F.Fab")
		)
		(fp_line
			(start -0.12065 0.3048)
			(end -0.67945 0.3048)
			(stroke
				(width 0.1)
				(type default)
			)
			(layer "F.Fab")
		)
		(fp_line
			(start -0.67945 0.3048)
			(end -0.67945 -0.305054)
			(stroke
				(width 0.1)
				(type default)
			)
			(layer "F.Fab")
		)
		(pad "1" smd circle
			(at -0.40005 0 90)
			(size 0 0)
			(layers "F.Cu" "F.Mask" "F.Paste")
			(net "IRQ_SML1_PMBUS_ALERT")
		)
		(pad "2" smd circle
			(at 0.40005 0 90)
			(size 0 0)
			(layers "F.Cu" "F.Mask" "F.Paste")
			(net "P3V3_AUX")
		)
	)
	(footprint ""
		(layer "F.Cu")
		(at 75.219306 -152.990804 90)
		(property "Reference" "PC150"
			(at 0 0 90)
			(layer "F.SilkS")
			(hide yes)
			(effects
				(font
					(size 1.27 1.27)
				)
			)
		)
		(property "Value" ""
			(at 0 0 90)
			(layer "F.Fab")
			(effects
				(font
					(size 1.27 1.27)
				)
			)
		)
		(duplicate_pad_numbers_are_jumpers no)
		(fp_line
			(start 1.524 -0.762)
			(end 1.524 0.762)
			(stroke
				(width 0.1524)
				(type default)
			)
			(layer "F.SilkS")
		)
		(fp_line
			(start -1.524 -0.762)
			(end 1.524 -0.762)
			(stroke
				(width 0.1524)
				(type default)
			)
			(layer "F.SilkS")
		)
		(fp_line
			(start 1.524 0.762)
			(end -1.524 0.762)
			(stroke
				(width 0.1524)
				(type default)
			)
			(layer "F.SilkS")
		)
		(fp_line
			(start -1.524 0.762)
			(end -1.524 -0.762)
			(stroke
				(width 0.1524)
				(type default)
			)
			(layer "F.SilkS")
		)
		(fp_line
			(start 1.1049 -0.724916)
			(end -1.1049 -0.724916)
			(stroke
				(width 0.1)
				(type default)
			)
			(layer "F.Fab")
		)
		(fp_line
			(start -1.1049 -0.724916)
			(end -1.1049 0.724916)
			(stroke
				(width 0.1)
				(type default)
			)
			(layer "F.Fab")
		)
		(fp_line
			(start 1.1049 0.724916)
			(end 1.1049 -0.724916)
			(stroke
				(width 0.1)
				(type default)
			)
			(layer "F.Fab")
		)
		(fp_line
			(start -1.1049 0.724916)
			(end 1.1049 0.724916)
			(stroke
				(width 0.1)
				(type default)
			)
			(layer "F.Fab")
		)
		(pad "1" smd rect
			(at -0.889 0 270)
			(size 1.016 1.27)
			(layers "F.Cu" "F.Mask" "F.Paste")
			(net "SW_P12V_AUX_PVDD18_S5_P1_FLT")
		)
		(pad "2" smd rect
			(at 0.889 0 270)
			(size 1.016 1.27)
			(layers "F.Cu" "F.Mask" "F.Paste")
			(net "GND")
		)
	)
	(footprint ""
		(layer "F.Cu")
		(at 32.601662 -419.249098 -90)
		(property "Reference" "R3273"
			(at 0 0 270)
			(layer "F.SilkS")
			(hide yes)
			(effects
				(font
					(size 1.27 1.27)
				)
			)
		)
		(property "Value" ""
			(at 0 0 270)
			(layer "F.Fab")
			(effects
				(font
					(size 1.27 1.27)
				)
			)
		)
		(duplicate_pad_numbers_are_jumpers no)
		(fp_line
			(start -0.7874 0.4064)
			(end -0.7874 -0.4064)
			(stroke
				(width 0.1524)
				(type default)
			)
			(layer "F.SilkS")
		)
		(fp_line
			(start 0.7874 0.4064)
			(end -0.7874 0.4064)
			(stroke
				(width 0.1524)
				(type default)
			)
			(layer "F.SilkS")
		)
		(fp_line
			(start -0.7874 -0.4064)
			(end 0.7874 -0.4064)
			(stroke
				(width 0.1524)
				(type default)
			)
			(layer "F.SilkS")
		)
		(fp_line
			(start 0.7874 -0.4064)
			(end 0.7874 0.4064)
			(stroke
				(width 0.1524)
				(type default)
			)
			(layer "F.SilkS")
		)
		(fp_line
			(start -0.67945 0.3048)
			(end -0.67945 -0.305054)
			(stroke
				(width 0.1)
				(type default)
			)
			(layer "F.Fab")
		)
		(fp_line
			(start -0.12065 0.3048)
			(end -0.67945 0.3048)
			(stroke
				(width 0.1)
				(type default)
			)
			(layer "F.Fab")
		)
		(fp_line
			(start 0.120396 0.3048)
			(end 0.120396 0.2794)
			(stroke
				(width 0.1)
				(type default)
			)
			(layer "F.Fab")
		)
		(fp_line
			(start 0.67945 0.3048)
			(end 0.120396 0.3048)
			(stroke
				(width 0.1)
				(type default)
			)
			(layer "F.Fab")
		)
		(fp_line
			(start -0.12065 0.2794)
			(end -0.12065 0.3048)
			(stroke
				(width 0.1)
				(type default)
			)
			(layer "F.Fab")
		)
		(fp_line
			(start 0.120396 0.2794)
			(end -0.12065 0.2794)
			(stroke
				(width 0.1)
				(type default)
			)
			(layer "F.Fab")
		)
		(fp_line
			(start -0.12065 -0.2794)
			(end 0.12065 -0.2794)
			(stroke
				(width 0.1)
				(type default)
			)
			(layer "F.Fab")
		)
		(fp_line
			(start 0.12065 -0.2794)
			(end 0.12065 -0.3048)
			(stroke
				(width 0.1)
				(type default)
			)
			(layer "F.Fab")
		)
		(fp_line
			(start 0.12065 -0.3048)
			(end 0.67945 -0.3048)
			(stroke
				(width 0.1)
				(type default)
			)
			(layer "F.Fab")
		)
		(fp_line
			(start 0.67945 -0.3048)
			(end 0.67945 0.3048)
			(stroke
				(width 0.1)
				(type default)
			)
			(layer "F.Fab")
		)
		(fp_line
			(start -0.67945 -0.305054)
			(end -0.12065 -0.305054)
			(stroke
				(width 0.1)
				(type default)
			)
			(layer "F.Fab")
		)
		(fp_line
			(start -0.12065 -0.305054)
			(end -0.12065 -0.2794)
			(stroke
				(width 0.1)
				(type default)
			)
			(layer "F.Fab")
		)
		(pad "1" smd circle
			(at -0.40005 0 270)
			(size 0 0)
			(layers "F.Cu" "F.Mask" "F.Paste")
			(net "FM_P2E_FGA")
		)
		(pad "2" smd circle
			(at 0.40005 0 270)
			(size 0 0)
			(layers "F.Cu" "F.Mask" "F.Paste")
			(net "GND")
		)
	)
	(footprint ""
		(layer "F.Cu")
		(at 252.88875 -99.065842 -90)
		(property "Reference" "U150"
			(at 1.886204 -3.446272 90)
			(unlocked yes)
			(layer "F.SilkS")
			(effects
				(font
					(size 0.7874 0.5842)
					(thickness 0.1524)
				)
				(justify left)
			)
		)
		(property "Value" ""
			(at 0 0 270)
			(layer "F.Fab")
			(effects
				(font
					(size 1.27 1.27)
				)
			)
		)
		(duplicate_pad_numbers_are_jumpers no)
		(fp_line
			(start -1.868932 2.549906)
			(end 1.868932 2.549906)
			(stroke
				(width 0.1524)
				(type default)
			)
			(layer "F.SilkS")
		)
		(fp_line
			(start 1.868932 2.549906)
			(end 1.868932 -2.549906)
			(stroke
				(width 0.1524)
				(type default)
			)
			(layer "F.SilkS")
		)
		(fp_line
			(start 0 -1.524)
			(end -1.025906 -2.549906)
			(stroke
				(width 0.1524)
				(type default)
			)
			(layer "F.SilkS")
		)
		(fp_line
			(start -1.868932 -2.549906)
			(end -1.868932 2.549906)
			(stroke
				(width 0.1524)
				(type default)
			)
			(layer "F.SilkS")
		)
		(fp_line
			(start -1.025906 -2.549906)
			(end -1.868932 -2.549906)
			(stroke
				(width 0.1524)
				(type default)
			)
			(layer "F.SilkS")
		)
		(fp_line
			(start 1.025906 -2.549906)
			(end 0 -1.524)
			(stroke
				(width 0.1524)
				(type default)
			)
			(layer "F.SilkS")
		)
		(fp_line
			(start 1.868932 -2.549906)
			(end 1.025906 -2.549906)
			(stroke
				(width 0.1524)
				(type default)
			)
			(layer "F.SilkS")
		)
		(fp_poly
			(pts
				(xy -3.7592 -2.295398) (xy -4.7752 -1.787398) (xy -4.7752 -2.803398)
			)
			(stroke
				(width 0)
				(type default)
			)
			(fill yes)
			(layer "F.SilkS")
		)
		(fp_line
			(start -2.249932 2.549906)
			(end 2.249932 2.549906)
			(stroke
				(width 0.1)
				(type default)
			)
			(layer "F.Fab")
		)
		(fp_line
			(start 2.249932 2.549906)
			(end 2.249932 -2.549906)
			(stroke
				(width 0.1)
				(type default)
			)
			(layer "F.Fab")
		)
		(fp_line
			(start -2.249932 -2.549906)
			(end -2.249932 2.549906)
			(stroke
				(width 0.1)
				(type default)
			)
			(layer "F.Fab")
		)
		(fp_line
			(start 2.249932 -2.549906)
			(end -2.249932 -2.549906)
			(stroke
				(width 0.1)
				(type default)
			)
			(layer "F.Fab")
		)
		(fp_poly
			(pts
				(xy -4.7752 -1.787398) (xy -4.7752 -2.803398) (xy -3.7592 -2.295398)
			)
			(stroke
				(width 0)
				(type default)
			)
			(fill yes)
			(layer "F.Fab")
		)
		(pad "1" smd rect
			(at -2.800096 -2.275078 180)
			(size 0.3556 1.6002)
			(layers "F.Cu" "F.Mask" "F.Paste")
			(net "PVDD18_S5_P0")
		)
		(pad "2" smd rect
			(at -2.800096 -1.625092 180)
			(size 0.3556 1.6002)
			(layers "F.Cu" "F.Mask" "F.Paste")
			(net "PVDD18_S5_P0")
		)
		(pad "3" smd rect
			(at -2.800096 -0.975106 180)
			(size 0.3556 1.6002)
			(layers "F.Cu" "F.Mask" "F.Paste")
			(net "JTAG_TCK")
		)
		(pad "4" smd rect
			(at -2.800096 -0.32512 180)
			(size 0.3556 1.6002)
			(layers "F.Cu" "F.Mask" "F.Paste")
			(net "JTAG_TMS")
		)
		(pad "5" smd rect
			(at -2.800096 0.32512 180)
			(size 0.3556 1.6002)
			(layers "F.Cu" "F.Mask" "F.Paste")
			(net "JTAG_TRST_N")
		)
		(pad "6" smd rect
			(at -2.800096 0.975106 180)
			(size 0.3556 1.6002)
			(layers "F.Cu" "F.Mask" "F.Paste")
			(net "JTAG_DBREQ_N")
		)
		(pad "7" smd rect
			(at -2.800096 1.625092 180)
			(size 0.3556 1.6002)
			(layers "F.Cu" "F.Mask" "F.Paste")
			(net "PVDD18_S5_P0")
		)
		(pad "8" smd rect
			(at -2.800096 2.275078 180)
			(size 0.3556 1.6002)
			(layers "F.Cu" "F.Mask" "F.Paste")
			(net "PVDD18_S5_P0")
		)
		(pad "9" smd rect
			(at 2.800096 2.275078 180)
			(size 0.3556 1.6002)
			(layers "F.Cu" "F.Mask" "F.Paste")
			(net "CPU0_JTAG_BUF_OE")
		)
		(pad "10" smd rect
			(at 2.800096 1.625092 180)
			(size 0.3556 1.6002)
			(layers "F.Cu" "F.Mask" "F.Paste")
			(net "GND")
		)
		(pad "11" smd rect
			(at 2.800096 0.975106 180)
			(size 0.3556 1.6002)
			(layers "F.Cu" "F.Mask" "F.Paste")
			(net "JTAG_P0_R_DBREQ_N")
		)
		(pad "12" smd rect
			(at 2.800096 0.32512 180)
			(size 0.3556 1.6002)
			(layers "F.Cu" "F.Mask" "F.Paste")
			(net "JTAG_P0_R_TRST_N")
		)
		(pad "13" smd rect
			(at 2.800096 -0.32512 180)
			(size 0.3556 1.6002)
			(layers "F.Cu" "F.Mask" "F.Paste")
			(net "JTAG_P0_R_TMS")
		)
		(pad "14" smd rect
			(at 2.800096 -0.975106 180)
			(size 0.3556 1.6002)
			(layers "F.Cu" "F.Mask" "F.Paste")
			(net "JTAG_P0_R_TCK")
		)
		(pad "15" smd rect
			(at 2.800096 -1.625092 180)
			(size 0.3556 1.6002)
			(layers "F.Cu" "F.Mask" "F.Paste")
			(net "PVDD18_S5_P0")
		)
		(pad "16" smd rect
			(at 2.800096 -2.275078 180)
			(size 0.3556 1.6002)
			(layers "F.Cu" "F.Mask" "F.Paste")
			(net "PVDD18_S5_P0")
		)
	)
	(footprint ""
		(layer "F.Cu")
		(at 92.759784 -33.06191)
		(property "Reference" "C38"
			(at 0 0 0)
			(layer "F.SilkS")
			(hide yes)
			(effects
				(font
					(size 1.27 1.27)
				)
			)
		)
		(property "Value" ""
			(at 0 0 0)
			(layer "F.Fab")
			(effects
				(font
					(size 1.27 1.27)
				)
			)
		)
		(duplicate_pad_numbers_are_jumpers no)
		(fp_line
			(start -0.7874 -0.4064)
			(end 0.7874 -0.4064)
			(stroke
				(width 0.1524)
				(type default)
			)
			(layer "F.SilkS")
		)
		(fp_line
			(start -0.7874 0.4064)
			(end -0.7874 -0.4064)
			(stroke
				(width 0.1524)
				(type default)
			)
			(layer "F.SilkS")
		)
		(fp_line
			(start 0.7874 -0.4064)
			(end 0.7874 0.4064)
			(stroke
				(width 0.1524)
				(type default)
			)
			(layer "F.SilkS")
		)
		(fp_line
			(start 0.7874 0.4064)
			(end -0.7874 0.4064)
			(stroke
				(width 0.1524)
				(type default)
			)
			(layer "F.SilkS")
		)
		(fp_line
			(start -0.67945 -0.305054)
			(end -0.12065 -0.305054)
			(stroke
				(width 0.1)
				(type default)
			)
			(layer "F.Fab")
		)
		(fp_line
			(start -0.67945 0.3048)
			(end -0.67945 -0.305054)
			(stroke
				(width 0.1)
				(type default)
			)
			(layer "F.Fab")
		)
		(fp_line
			(start -0.12065 -0.305054)
			(end -0.12065 -0.2794)
			(stroke
				(width 0.1)
				(type default)
			)
			(layer "F.Fab")
		)
		(fp_line
			(start -0.12065 -0.2794)
			(end 0.12065 -0.2794)
			(stroke
				(width 0.1)
				(type default)
			)
			(layer "F.Fab")
		)
		(fp_line
			(start -0.12065 0.2794)
			(end -0.12065 0.3048)
			(stroke
				(width 0.1)
				(type default)
			)
			(layer "F.Fab")
		)
		(fp_line
			(start -0.12065 0.3048)
			(end -0.67945 0.3048)
			(stroke
				(width 0.1)
				(type default)
			)
			(layer "F.Fab")
		)
		(fp_line
			(start 0.120396 0.2794)
			(end -0.12065 0.2794)
			(stroke
				(width 0.1)
				(type default)
			)
			(layer "F.Fab")
		)
		(fp_line
			(start 0.120396 0.3048)
			(end 0.120396 0.2794)
			(stroke
				(width 0.1)
				(type default)
			)
			(layer "F.Fab")
		)
		(fp_line
			(start 0.12065 -0.3048)
			(end 0.67945 -0.3048)
			(stroke
				(width 0.1)
				(type default)
			)
			(layer "F.Fab")
		)
		(fp_line
			(start 0.12065 -0.2794)
			(end 0.12065 -0.3048)
			(stroke
				(width 0.1)
				(type default)
			)
			(layer "F.Fab")
		)
		(fp_line
			(start 0.67945 -0.3048)
			(end 0.67945 0.3048)
			(stroke
				(width 0.1)
				(type default)
			)
			(layer "F.Fab")
		)
		(fp_line
			(start 0.67945 0.3048)
			(end 0.120396 0.3048)
			(stroke
				(width 0.1)
				(type default)
			)
			(layer "F.Fab")
		)
		(pad "1" smd circle
			(at -0.40005 0)
			(size 0 0)
			(layers "F.Cu" "F.Mask" "F.Paste")
			(net "P3V3_AUX")
		)
		(pad "2" smd circle
			(at 0.40005 0)
			(size 0 0)
			(layers "F.Cu" "F.Mask" "F.Paste")
			(net "GND")
		)
	)
)
